# BASEBOARD_FAB2 (Tioga Pass) — schematic netlist excerpt (pin names and nets, part order shuffled) for the footprints in the layout excerpt that follows; sources: Cadence DE-HDL packaged netlist, KiCad conversion of Wiwynn_Tioga_Pass_MB.brd

C2D33  CAP_A  22.0UF 4V 20% X6S  pkg 0603V  page 76 : A = PVCCIN_CPU1 ; B = GND
C5D14  CAP_A  22.0UF 4V 20% X6S  pkg 0603V  page 42 : A = PVCCIN_CPU0 ; B = GND
R4F4  RES  1.00K 1% CHIP  pkg 0402  page 98 : A = PVDDQ_ABC ; B = M_A_VREF
C1G20  CAP  22UF 4V 20% X6S  pkg 0805LF  page 224 : A = PVDDQ_GHJ ; B = GND

(kicad_pcb
	(version 20260206)
	(generator "pcbnew")
	(generator_version "10.0")
	(general
		(thickness 1.6)
		(legacy_teardrops no)
	)
	(paper "A4")
	(title_block
		(title "Wiwynn_Tioga_Pass_MB.brd")
		(comment 1 "Tioga Pass / footprints 64-67 of 4770")
	)
	(layers
		(0 "F.Cu" signal "TOP")
		(4 "In1.Cu" signal "L2GND")
		(6 "In2.Cu" signal "L3")
		(8 "In3.Cu" signal "L4GND")
		(10 "In4.Cu" signal "L5")
		(12 "In5.Cu" signal "L6GND")
		(14 "In6.Cu" signal "L7VCC")
		(16 "In7.Cu" signal "L8VCC")
		(18 "In8.Cu" signal "L9GND")
		(20 "In9.Cu" signal "L10")
		(22 "In10.Cu" signal "L11GND")
		(24 "In11.Cu" signal "L12")
		(26 "In12.Cu" signal "L13GND")
		(2 "B.Cu" signal "BOTTOM")
		(9 "F.Adhes" user "F.Adhesive")
		(11 "B.Adhes" user "B.Adhesive")
		(13 "F.Paste" user "Package Geometry/Pastemask Top")
		(15 "B.Paste" user "Package Geometry/Pastemask Bottom")
		(5 "F.SilkS" user "Ref Des/Silkscreen Top")
		(7 "B.SilkS" user "Ref Des/Silkscreen Bottom")
		(1 "F.Mask" user "Board Geometry/Soldermask Top")
		(3 "B.Mask" user "Board Geometry/Soldermask Bottom")
		(17 "Dwgs.User" user "User.Drawings")
		(19 "Cmts.User" user "User.Comments")
		(21 "Eco1.User" user "User.Eco1")
		(23 "Eco2.User" user "User.Eco2")
		(25 "Edge.Cuts" user "Board Geometry/Outline")
		(27 "Margin" user)
		(31 "F.CrtYd" user "Package Geometry/Place Bound Top")
		(29 "B.CrtYd" user "Package Geometry/Place Bound Bottom")
		(35 "F.Fab" user "Ref Des/Assembly Top")
		(33 "B.Fab" user "Ref Des/Assembly Bottom")
	)
	(footprint ""
		(layer "F.Cu")
		(at 19.220434 -2.643378 -90)
		(property "Reference" "C1G20"
			(at 0 0 270)
			(layer "F.SilkS")
			(hide yes)
			(effects
				(font
					(size 1.27 1.27)
				)
			)
		)
		(property "Value" ""
			(at 0 0 270)
			(layer "F.Fab")
			(effects
				(font
					(size 1.27 1.27)
				)
			)
		)
		(duplicate_pad_numbers_are_jumpers no)
		(fp_rect
			(start -0.7239 -0.2159)
			(end 0.7239 1.9939)
			(stroke
				(width 0)
				(type default)
			)
			(fill no)
			(layer "F.CrtYd")
		)
		(fp_line
			(start -0.7239 1.9939)
			(end 0.7239 1.9939)
			(stroke
				(width 0.1)
				(type default)
			)
			(layer "F.Fab")
		)
		(fp_line
			(start 0.7239 1.9939)
			(end 0.7239 -0.2159)
			(stroke
				(width 0.1)
				(type default)
			)
			(layer "F.Fab")
		)
		(fp_line
			(start -0.7239 -0.2159)
			(end -0.7239 1.9939)
			(stroke
				(width 0.1)
				(type default)
			)
			(layer "F.Fab")
		)
		(fp_line
			(start 0.7239 -0.2159)
			(end -0.7239 -0.2159)
			(stroke
				(width 0.1)
				(type default)
			)
			(layer "F.Fab")
		)
		(pad "1" smd rect
			(at 0 0 270)
			(size 1.27 1.016)
			(layers "F.Cu" "F.Mask" "F.Paste")
			(net "PVDDQ_GHJ")
		)
		(pad "2" smd rect
			(at 0 1.778 270)
			(size 1.27 1.016)
			(layers "F.Cu" "F.Mask" "F.Paste")
			(net "GND")
		)
		(zone
			(layer "F.Cu")
			(hatch none 0.5)
			(connect_pads
				(clearance 0)
			)
			(min_thickness 0.25)
			(keepout
				(tracks not_allowed)
				(vias allowed)
				(pads allowed)
				(copperpour not_allowed)
				(footprints allowed)
			)
			(placement
				(enabled no)
				(sheetname "")
			)
			(fill
				(thermal_gap 0.5)
				(thermal_bridge_width 0.5)
				(island_removal_mode 0)
			)
			(polygon
				(pts
					(xy 18.712434 -3.278378) (xy 17.950434 -3.278378) (xy 17.950434 -2.008378) (xy 18.712434 -2.008378)
				)
			)
		)
	)
	(footprint ""
		(layer "F.Cu")
		(at 261.9502 -79.6036 180)
		(property "Reference" "C5D14"
			(at 0 0 180)
			(layer "F.SilkS")
			(hide yes)
			(effects
				(font
					(size 1.27 1.27)
				)
			)
		)
		(property "Value" ""
			(at 0 0 180)
			(layer "F.Fab")
			(effects
				(font
					(size 1.27 1.27)
				)
			)
		)
		(duplicate_pad_numbers_are_jumpers no)
		(fp_poly
			(pts
				(xy -0.4953 -0.2032) (xy 0.4953 -0.2032) (xy 0.4953 1.6002) (xy -0.4953 1.6002)
			)
			(stroke
				(width 0)
				(type default)
			)
			(fill no)
			(layer "F.CrtYd")
		)
		(fp_line
			(start 0.4953 1.6002)
			(end -0.4953 1.6002)
			(stroke
				(width 0.1)
				(type default)
			)
			(layer "F.Fab")
		)
		(fp_line
			(start 0.4953 -0.2032)
			(end 0.4953 1.6002)
			(stroke
				(width 0.1)
				(type default)
			)
			(layer "F.Fab")
		)
		(fp_line
			(start -0.4953 1.6002)
			(end -0.4953 -0.2032)
			(stroke
				(width 0.1)
				(type default)
			)
			(layer "F.Fab")
		)
		(fp_line
			(start -0.4953 -0.2032)
			(end 0.4953 -0.2032)
			(stroke
				(width 0.1)
				(type default)
			)
			(layer "F.Fab")
		)
		(pad "1" smd rect
			(at 0 0 180)
			(size 0.762 0.889)
			(layers "F.Cu" "F.Mask" "F.Paste")
			(net "PVCCIN_CPU0")
		)
		(pad "2" smd rect
			(at 0 1.397 180)
			(size 0.762 0.889)
			(layers "F.Cu" "F.Mask" "F.Paste")
			(net "GND")
		)
		(zone
			(layer "F.Cu")
			(hatch none 0.5)
			(connect_pads
				(clearance 0)
			)
			(min_thickness 0.25)
			(keepout
				(tracks not_allowed)
				(vias allowed)
				(pads allowed)
				(copperpour not_allowed)
				(footprints allowed)
			)
			(placement
				(enabled no)
				(sheetname "")
			)
			(fill
				(thermal_gap 0.5)
				(thermal_bridge_width 0.5)
				(island_removal_mode 0)
			)
			(polygon
				(pts
					(xy 262.3312 -80.0481) (xy 261.5692 -80.0481) (xy 261.5692 -80.5561) (xy 262.3312 -80.5561)
				)
			)
		)
	)
	(footprint ""
		(layer "F.Cu")
		(at 96.94164 -73.318116)
		(property "Reference" "C2D33"
			(at 0 0 0)
			(layer "F.SilkS")
			(hide yes)
			(effects
				(font
					(size 1.27 1.27)
				)
			)
		)
		(property "Value" ""
			(at 0 0 0)
			(layer "F.Fab")
			(effects
				(font
					(size 1.27 1.27)
				)
			)
		)
		(duplicate_pad_numbers_are_jumpers no)
		(fp_poly
			(pts
				(xy -0.4953 -0.2032) (xy 0.4953 -0.2032) (xy 0.4953 1.6002) (xy -0.4953 1.6002)
			)
			(stroke
				(width 0)
				(type default)
			)
			(fill no)
			(layer "F.CrtYd")
		)
		(fp_line
			(start -0.4953 -0.2032)
			(end 0.4953 -0.2032)
			(stroke
				(width 0.1)
				(type default)
			)
			(layer "F.Fab")
		)
		(fp_line
			(start -0.4953 1.6002)
			(end -0.4953 -0.2032)
			(stroke
				(width 0.1)
				(type default)
			)
			(layer "F.Fab")
		)
		(fp_line
			(start 0.4953 -0.2032)
			(end 0.4953 1.6002)
			(stroke
				(width 0.1)
				(type default)
			)
			(layer "F.Fab")
		)
		(fp_line
			(start 0.4953 1.6002)
			(end -0.4953 1.6002)
			(stroke
				(width 0.1)
				(type default)
			)
			(layer "F.Fab")
		)
		(pad "1" smd rect
			(at 0 0)
			(size 0.762 0.889)
			(layers "F.Cu" "F.Mask" "F.Paste")
			(net "PVCCIN_CPU1")
		)
		(pad "2" smd rect
			(at 0 1.397)
			(size 0.762 0.889)
			(layers "F.Cu" "F.Mask" "F.Paste")
			(net "GND")
		)
		(zone
			(layer "F.Cu")
			(hatch none 0.5)
			(connect_pads
				(clearance 0)
			)
			(min_thickness 0.25)
			(keepout
				(tracks not_allowed)
				(vias allowed)
				(pads allowed)
				(copperpour not_allowed)
				(footprints allowed)
			)
			(placement
				(enabled no)
				(sheetname "")
			)
			(fill
				(thermal_gap 0.5)
				(thermal_bridge_width 0.5)
				(island_removal_mode 0)
			)
			(polygon
				(pts
					(xy 96.56064 -72.873616) (xy 97.32264 -72.873616) (xy 97.32264 -72.365616) (xy 96.56064 -72.365616)
				)
			)
		)
	)
	(footprint ""
		(layer "F.Cu")
		(at 193.675 -23.396194)
		(property "Reference" "R4F4"
			(at 0 0 0)
			(layer "F.SilkS")
			(hide yes)
			(effects
				(font
					(size 1.27 1.27)
				)
			)
		)
		(property "Value" ""
			(at 0 0 0)
			(layer "F.Fab")
			(effects
				(font
					(size 1.27 1.27)
				)
			)
		)
		(duplicate_pad_numbers_are_jumpers no)
		(fp_poly
			(pts
				(xy -0.2794 -0.1016) (xy 0.2794 -0.1016) (xy 0.2794 0.9906) (xy -0.2794 0.9906)
			)
			(stroke
				(width 0)
				(type default)
			)
			(fill no)
			(layer "F.CrtYd")
		)
		(fp_line
			(start -0.2794 -0.1016)
			(end -0.2794 0.9906)
			(stroke
				(width 0.1)
				(type default)
			)
			(layer "F.Fab")
		)
		(fp_line
			(start -0.2794 0.9906)
			(end 0.2794 0.9906)
			(stroke
				(width 0.1)
				(type default)
			)
			(layer "F.Fab")
		)
		(fp_line
			(start 0.2794 -0.1016)
			(end -0.2794 -0.1016)
			(stroke
				(width 0.1)
				(type default)
			)
			(layer "F.Fab")
		)
		(fp_line
			(start 0.2794 0.9906)
			(end 0.2794 -0.1016)
			(stroke
				(width 0.1)
				(type default)
			)
			(layer "F.Fab")
		)
		(pad "1" smd rect
			(at 0 0)
			(size 0.508 0.508)
			(layers "F.Cu" "F.Mask" "F.Paste")
			(net "PVDDQ_ABC")
		)
		(pad "2" smd rect
			(at 0 0.889)
			(size 0.508 0.508)
			(layers "F.Cu" "F.Mask" "F.Paste")
			(net "M_A_VREF")
		)
		(zone
			(layer "F.Cu")
			(hatch none 0.5)
			(connect_pads
				(clearance 0)
			)
			(min_thickness 0.25)
			(keepout
				(tracks allowed)
				(vias not_allowed)
				(pads allowed)
				(copperpour not_allowed)
				(footprints allowed)
			)
			(placement
				(enabled no)
				(sheetname "")
			)
			(fill
				(thermal_gap 0.5)
				(thermal_bridge_width 0.5)
				(island_removal_mode 0)
			)
			(polygon
				(pts
					(xy 193.421 -23.142194) (xy 193.929 -23.142194) (xy 193.929 -22.761194) (xy 193.421 -22.761194)
				)
			)
		)
		(zone
			(layer "F.Cu")
			(hatch none 0.5)
			(connect_pads
				(clearance 0)
			)
			(min_thickness 0.25)
			(keepout
				(tracks not_allowed)
				(vias allowed)
				(pads allowed)
				(copperpour not_allowed)
				(footprints allowed)
			)
			(placement
				(enabled no)
				(sheetname "")
			)
			(fill
				(thermal_gap 0.5)
				(thermal_bridge_width 0.5)
				(island_removal_mode 0)
			)
			(polygon
				(pts
					(xy 193.421 -22.761194) (xy 193.929 -22.761194) (xy 193.929 -23.142194) (xy 193.421 -23.142194)
				)
			)
		)
	)
)
